(kicad_pcb
	(version 20241229)
	(generator "pcbnew")
	(generator_version "9.0")
	(general
		(thickness 1.294)
		(legacy_teardrops no)
	)
	(paper "A3")
	(title_block
		(title "Kintex 410T devboard")
		(date "2024-04-03")
		(rev "1.1.2")
		(comment 9 "footprints 661-666 of 975")
	)
	(layers
		(0 "F.Cu" mixed)
		(4 "In1.Cu" power)
		(6 "In2.Cu" power)
		(8 "In3.Cu" mixed)
		(10 "In4.Cu" power)
		(12 "In5.Cu" mixed)
		(14 "In6.Cu" power)
		(16 "In7.Cu" mixed)
		(18 "In8.Cu" power)
		(2 "B.Cu" mixed)
		(9 "F.Adhes" user "F.Adhesive")
		(11 "B.Adhes" user "B.Adhesive")
		(13 "F.Paste" user)
		(15 "B.Paste" user)
		(5 "F.SilkS" user "F.Silkscreen")
		(7 "B.SilkS" user "B.Silkscreen")
		(1 "F.Mask" user)
		(3 "B.Mask" user)
		(17 "Dwgs.User" user "User.Drawings")
		(19 "Cmts.User" user "User.Comments")
		(21 "Eco1.User" user "User.Eco1")
		(23 "Eco2.User" user "User.Eco2")
		(25 "Edge.Cuts" user)
		(27 "Margin" user)
		(31 "F.CrtYd" user "F.Courtyard")
		(29 "B.CrtYd" user "B.Courtyard")
		(35 "F.Fab" user)
		(33 "B.Fab" user)
	)
	(footprint "antmicro-footprints:C_0402_1005Metric"
		(layer "B.Cu")
		(at 204.5 124 -90)
		(descr "Capacitor SMD 0402")
		(tags "capacitor SMD 0402")
		(property "Reference" "C81"
			(at -30.975 -28.65 90)
			(layer "B.SilkS")
			(effects
				(font
					(size 0.7 0.7)
					(thickness 0.15)
				)
				(justify left bottom mirror)
			)
		)
		(property "Value" "C_100n_0402"
			(at 0 -1.169 90)
			(layer "B.Fab")
			(effects
				(font
					(size 0.7 0.7)
					(thickness 0.15)
				)
				(justify left bottom mirror)
			)
		)
		(property "Description" "SMD Multilayer Ceramic Capacitor, 0.1 µF, 50 V, 0402 [1005 Metric], ± 10%, X5R, GRM Series"
			(at 0 0 270)
			(layer "F.Fab")
			(hide yes)
			(effects
				(font
					(size 1.27 1.27)
					(thickness 0.15)
				)
			)
		)
		(property "Author" "Antmicro"
			(at 80.5 328.5 0)
			(layer "B.Fab")
			(hide yes)
			(effects
				(font
					(size 1 1)
					(thickness 0.15)
				)
				(justify mirror)
			)
		)
		(property "Dielectric" "X5R"
			(at 80.5 328.5 0)
			(layer "B.Fab")
			(hide yes)
			(effects
				(font
					(size 1 1)
					(thickness 0.15)
				)
				(justify mirror)
			)
		)
		(property "License" "Apache-2.0"
			(at 80.5 328.5 0)
			(layer "B.Fab")
			(hide yes)
			(effects
				(font
					(size 1 1)
					(thickness 0.15)
				)
				(justify mirror)
			)
		)
		(property "MPN" "GRM155R61H104KE14D"
			(at 80.5 328.5 0)
			(layer "B.Fab")
			(hide yes)
			(effects
				(font
					(size 1 1)
					(thickness 0.15)
				)
				(justify mirror)
			)
		)
		(property "Manufacturer" "Murata"
			(at 80.5 328.5 0)
			(layer "B.Fab")
			(hide yes)
			(effects
				(font
					(size 1 1)
					(thickness 0.15)
				)
				(justify mirror)
			)
		)
		(property "Val" "100n"
			(at 80.5 328.5 0)
			(layer "B.Fab")
			(hide yes)
			(effects
				(font
					(size 1 1)
					(thickness 0.15)
				)
				(justify mirror)
			)
		)
		(property "Voltage" "50V"
			(at 80.5 328.5 0)
			(layer "B.Fab")
			(hide yes)
			(effects
				(font
					(size 1 1)
					(thickness 0.15)
				)
				(justify mirror)
			)
		)
		(sheetname "FPGA Bank 16 & 17")
		(sheetfile "fpga-bank-16-17.kicad_sch")
		(attr smd)
		(fp_rect
			(start -0.925 0.47)
			(end 0.925 -0.47)
			(stroke
				(width 0.05)
				(type default)
			)
			(fill no)
			(layer "B.CrtYd")
		)
		(fp_line
			(start -0.494 0.25)
			(end 0.504 0.25)
			(stroke
				(width 0.15)
				(type solid)
			)
			(layer "B.Fab")
		)
		(fp_line
			(start 0.504 0.25)
			(end 0.504 -0.248)
			(stroke
				(width 0.15)
				(type solid)
			)
			(layer "B.Fab")
		)
		(fp_line
			(start -0.494 -0.248)
			(end -0.494 0.25)
			(stroke
				(width 0.15)
				(type solid)
			)
			(layer "B.Fab")
		)
		(fp_line
			(start 0.504 -0.248)
			(end -0.494 -0.248)
			(stroke
				(width 0.15)
				(type solid)
			)
			(layer "B.Fab")
		)
		(pad "1" smd roundrect
			(at -0.48 0 270)
			(size 0.59 0.64)
			(layers "B.Cu" "B.Mask" "B.Paste")
			(roundrect_rratio 0.25)
			(net 1 "GND")
			(pintype "passive")
		)
		(pad "2" smd roundrect
			(at 0.48 0 270)
			(size 0.59 0.64)
			(layers "B.Cu" "B.Mask" "B.Paste")
			(roundrect_rratio 0.25)
			(net 24 "+3V3")
			(pintype "passive")
		)
	)
	(footprint "antmicro-footprints:R_0402_1005Metric"
		(layer "B.Cu")
		(at 166.55 185.95 -90)
		(descr "Resistor SMD 0402")
		(tags "resistor SMD 0402")
		(property "Reference" "R318"
			(at -3.625 -0.525 90)
			(layer "B.SilkS")
			(effects
				(font
					(size 0.7 0.7)
					(thickness 0.15)
				)
				(justify left bottom mirror)
			)
		)
		(property "Value" "R_47k_0402"
			(at 0 -1.4 90)
			(layer "B.Fab")
			(effects
				(font
					(size 0.7 0.7)
					(thickness 0.15)
				)
				(justify left bottom mirror)
			)
		)
		(property "Description" "SMD Chip Resistor, 47 kohm, ± 1%, 62.5 mW, 0402 [1005 Metric], Thick Film, General Purpose"
			(at 0 0 270)
			(layer "F.Fab")
			(hide yes)
			(effects
				(font
					(size 1.27 1.27)
					(thickness 0.15)
				)
			)
		)
		(property "Author" "Antmicro"
			(at -19.4 352.5 0)
			(layer "B.Fab")
			(hide yes)
			(effects
				(font
					(size 1 1)
					(thickness 0.15)
				)
				(justify mirror)
			)
		)
		(property "License" "Apache-2.0"
			(at -19.4 352.5 0)
			(layer "B.Fab")
			(hide yes)
			(effects
				(font
					(size 1 1)
					(thickness 0.15)
				)
				(justify mirror)
			)
		)
		(property "MPN" "CR0402-FX-4702GLF"
			(at -19.4 352.5 0)
			(layer "B.Fab")
			(hide yes)
			(effects
				(font
					(size 1 1)
					(thickness 0.15)
				)
				(justify mirror)
			)
		)
		(property "Manufacturer" "Bourns"
			(at -19.4 352.5 0)
			(layer "B.Fab")
			(hide yes)
			(effects
				(font
					(size 1 1)
					(thickness 0.15)
				)
				(justify mirror)
			)
		)
		(property "Tolerance" "1%"
			(at -19.4 352.5 0)
			(layer "B.Fab")
			(hide yes)
			(effects
				(font
					(size 1 1)
					(thickness 0.15)
				)
				(justify mirror)
			)
		)
		(property "Val" "47k"
			(at -19.4 352.5 0)
			(layer "B.Fab")
			(hide yes)
			(effects
				(font
					(size 1 1)
					(thickness 0.15)
				)
				(justify mirror)
			)
		)
		(sheetname "DC-DC Converters")
		(sheetfile "dc-dc.kicad_sch")
		(attr smd)
		(fp_rect
			(start -0.925 0.47)
			(end 0.925 -0.47)
			(stroke
				(width 0.05)
				(type default)
			)
			(fill no)
			(layer "B.CrtYd")
		)
		(fp_rect
			(start -0.5 0.25)
			(end 0.5 -0.25)
			(stroke
				(width 0.15)
				(type solid)
			)
			(fill no)
			(layer "B.Fab")
		)
		(pad "1" smd roundrect
			(at -0.48 0 270)
			(size 0.59 0.64)
			(layers "B.Cu" "B.Mask" "B.Paste")
			(roundrect_rratio 0.25)
			(net 966 "/DC-DC Converters/EN1")
			(pintype "passive")
		)
		(pad "2" smd roundrect
			(at 0.48 0 270)
			(size 0.59 0.64)
			(layers "B.Cu" "B.Mask" "B.Paste")
			(roundrect_rratio 0.25)
			(net 37 "+3V3_AON")
			(pintype "passive")
		)
	)
	(footprint "antmicro-footprints:C_0201"
		(layer "B.Cu")
		(at 186.723727 121.723727 -45)
		(descr "Capacitor SMD 0201")
		(tags "capacitor SMD 0201")
		(property "Reference" "C162"
			(at -0.493174 0.883883 180)
			(layer "B.SilkS")
			(effects
				(font
					(size 0.7 0.7)
					(thickness 0.15)
				)
				(justify left bottom mirror)
			)
		)
		(property "Value" "C_4u7_0201"
			(at 0 -1.399999 135)
			(layer "B.Fab")
			(effects
				(font
					(size 0.7 0.7)
					(thickness 0.15)
				)
				(justify left bottom mirror)
			)
		)
		(property "Description" "SMD Multilayer Ceramic Capacitor, 4.7 µF, 6.3 V, 0201 [0603 Metric], ± 20%, X5R, GRM Series"
			(at 0 0 315)
			(layer "F.Fab")
			(hide yes)
			(effects
				(font
					(size 1.27 1.27)
					(thickness 0.15)
				)
			)
		)
		(property "Author" "Antmicro"
			(at -31.381559 167.685667 0)
			(layer "B.Fab")
			(hide yes)
			(effects
				(font
					(size 1 1)
					(thickness 0.15)
				)
				(justify mirror)
			)
		)
		(property "Dielectric" ""
			(at -31.381559 167.685667 0)
			(layer "B.Fab")
			(hide yes)
			(effects
				(font
					(size 1 1)
					(thickness 0.15)
				)
				(justify mirror)
			)
		)
		(property "License" "Apache-2.0"
			(at -31.381559 167.685667 0)
			(layer "B.Fab")
			(hide yes)
			(effects
				(font
					(size 1 1)
					(thickness 0.15)
				)
				(justify mirror)
			)
		)
		(property "MPN" "GRM035R60J475ME15D"
			(at -31.381559 167.685667 0)
			(layer "B.Fab")
			(hide yes)
			(effects
				(font
					(size 1 1)
					(thickness 0.15)
				)
				(justify mirror)
			)
		)
		(property "Manufacturer" "Murata"
			(at -31.381559 167.685667 0)
			(layer "B.Fab")
			(hide yes)
			(effects
				(font
					(size 1 1)
					(thickness 0.15)
				)
				(justify mirror)
			)
		)
		(property "Val" "4u7"
			(at -31.381559 167.685667 0)
			(layer "B.Fab")
			(hide yes)
			(effects
				(font
					(size 1 1)
					(thickness 0.15)
				)
				(justify mirror)
			)
		)
		(property "Voltage" ""
			(at -31.381559 167.685667 0)
			(layer "B.Fab")
			(hide yes)
			(effects
				(font
					(size 1 1)
					(thickness 0.15)
				)
				(justify mirror)
			)
		)
		(sheetname "FPGA supply")
		(sheetfile "fpga-supply.kicad_sch")
		(attr smd)
		(fp_poly
			(pts
				(xy -0.7 0.35) (xy 0.7 0.35) (xy 0.7 -0.35) (xy -0.7 -0.35)
			)
			(stroke
				(width 0.05)
				(type default)
			)
			(fill no)
			(layer "B.CrtYd")
		)
		(fp_poly
			(pts
				(xy 0.3 -0.15) (xy -0.301 -0.15) (xy -0.301 0.149) (xy 0.3 0.149)
			)
			(stroke
				(width 0.15)
				(type solid)
			)
			(fill no)
			(layer "B.Fab")
		)
		(pad "" smd roundrect
			(at -0.349 0.002 315)
			(size 0.318 0.36)
			(layers "B.Paste")
			(roundrect_rratio 0.25)
		)
		(pad "" smd roundrect
			(at 0.341 0.002 315)
			(size 0.318 0.36)
			(layers "B.Paste")
			(roundrect_rratio 0.25)
		)
		(pad "1" smd roundrect
			(at -0.321 0.002 315)
			(size 0.46 0.4)
			(layers "B.Cu" "B.Mask")
			(roundrect_rratio 0.25)
			(net 1 "GND")
			(pintype "passive")
		)
		(pad "2" smd roundrect
			(at 0.32 0.002 315)
			(size 0.46 0.4)
			(layers "B.Cu" "B.Mask")
			(roundrect_rratio 0.25)
			(net 8 "+1V2_MGTAVTT")
			(pintype "passive")
		)
	)
	(footprint "antmicro-footprints:NetTie-2_SMD_Pad0.127mm"
		(layer "B.Cu")
		(at 253.301 148.4 -90)
		(descr "Net tie, 2 pin, 0.127mm  SMD pads")
		(tags "net tie")
		(property "Reference" "NT9"
			(at -0.128 1.345 90)
			(layer "B.SilkS")
			(hide yes)
			(effects
				(font
					(size 0.7 0.7)
					(thickness 0.15)
				)
				(justify left bottom mirror)
			)
		)
		(property "Value" "Net-Tie_2"
			(at 0 -1.199 90)
			(layer "B.Fab")
			(effects
				(font
					(size 0.7 0.7)
					(thickness 0.15)
				)
				(justify left bottom mirror)
			)
		)
		(property "Description" "Net tie, 2 pins"
			(at 0 0 270)
			(layer "F.Fab")
			(hide yes)
			(effects
				(font
					(size 1.27 1.27)
					(thickness 0.15)
				)
			)
		)
		(property "Author" "Antmicro"
			(at 104.901 401.701 0)
			(layer "B.Fab")
			(hide yes)
			(effects
				(font
					(size 1 1)
					(thickness 0.15)
				)
				(justify mirror)
			)
		)
		(property "License" "Apache-2.0"
			(at 104.901 401.701 0)
			(layer "B.Fab")
			(hide yes)
			(effects
				(font
					(size 1 1)
					(thickness 0.15)
				)
				(justify mirror)
			)
		)
		(property "MPN" ""
			(at 104.901 401.701 0)
			(layer "B.Fab")
			(hide yes)
			(effects
				(font
					(size 1 1)
					(thickness 0.15)
				)
				(justify mirror)
			)
		)
		(property "Manufacturer" ""
			(at 104.901 401.701 0)
			(layer "B.Fab")
			(hide yes)
			(effects
				(font
					(size 1 1)
					(thickness 0.15)
				)
				(justify mirror)
			)
		)
		(sheetname "FPGA Bank 14 & 15")
		(sheetfile "fpga-bank-14-15.kicad_sch")
		(attr exclude_from_pos_files)
		(net_tie_pad_groups "1, 2")
		(fp_poly
			(pts
				(xy -0.0635 0.0635) (xy 0.0625 0.0635) (xy 0.0625 -0.0635) (xy -0.0635 -0.0635)
			)
			(stroke
				(width 0)
				(type solid)
			)
			(fill yes)
			(layer "B.Cu")
		)
		(pad "1" smd roundrect
			(at -0.127 0 90)
			(size 0.127 0.127)
			(layers "B.Cu")
			(roundrect_rratio 0.5)
			(chamfer_ratio 0)
			(chamfer top_left bottom_left)
			(net 1294 "/USB_SPI.MISO")
			(pinfunction "1")
			(pintype "passive")
		)
		(pad "2" smd roundrect
			(at 0.126 0 270)
			(size 0.127 0.127)
			(layers "B.Cu")
			(roundrect_rratio 0.5)
			(chamfer_ratio 0)
			(chamfer top_left bottom_left)
			(net 1319 "/SUP_MCU.MISO")
			(pinfunction "2")
			(pintype "passive")
		)
	)
	(footprint "antmicro-footprints:C_0402_1005Metric"
		(layer "B.Cu")
		(at 198.325 133.2)
		(descr "Capacitor SMD 0402")
		(tags "capacitor SMD 0402")
		(property "Reference" "C58"
			(at 26.05 -28.1 180)
			(layer "B.SilkS")
			(effects
				(font
					(size 0.7 0.7)
					(thickness 0.15)
				)
				(justify left bottom mirror)
			)
		)
		(property "Value" "C_100n_0402"
			(at 0 -1.169 180)
			(layer "B.Fab")
			(effects
				(font
					(size 0.7 0.7)
					(thickness 0.15)
				)
				(justify left bottom mirror)
			)
		)
		(property "Description" "SMD Multilayer Ceramic Capacitor, 0.1 µF, 50 V, 0402 [1005 Metric], ± 10%, X5R, GRM Series"
			(at 0 0 0)
			(layer "F.Fab")
			(hide yes)
			(effects
				(font
					(size 1.27 1.27)
					(thickness 0.15)
				)
			)
		)
		(property "Author" "Antmicro"
			(at 0 0 0)
			(layer "B.Fab")
			(hide yes)
			(effects
				(font
					(size 1 1)
					(thickness 0.15)
				)
				(justify mirror)
			)
		)
		(property "Dielectric" "X5R"
			(at 0 0 0)
			(layer "B.Fab")
			(hide yes)
			(effects
				(font
					(size 1 1)
					(thickness 0.15)
				)
				(justify mirror)
			)
		)
		(property "License" "Apache-2.0"
			(at 0 0 0)
			(layer "B.Fab")
			(hide yes)
			(effects
				(font
					(size 1 1)
					(thickness 0.15)
				)
				(justify mirror)
			)
		)
		(property "MPN" "GRM155R61H104KE14D"
			(at 0 0 0)
			(layer "B.Fab")
			(hide yes)
			(effects
				(font
					(size 1 1)
					(thickness 0.15)
				)
				(justify mirror)
			)
		)
		(property "Manufacturer" "Murata"
			(at 0 0 0)
			(layer "B.Fab")
			(hide yes)
			(effects
				(font
					(size 1 1)
					(thickness 0.15)
				)
				(justify mirror)
			)
		)
		(property "Val" "100n"
			(at 0 0 0)
			(layer "B.Fab")
			(hide yes)
			(effects
				(font
					(size 1 1)
					(thickness 0.15)
				)
				(justify mirror)
			)
		)
		(property "Voltage" "50V"
			(at 0 0 0)
			(layer "B.Fab")
			(hide yes)
			(effects
				(font
					(size 1 1)
					(thickness 0.15)
				)
				(justify mirror)
			)
		)
		(sheetname "FPGA supply")
		(sheetfile "fpga-supply.kicad_sch")
		(attr smd)
		(fp_rect
			(start -0.925 0.47)
			(end 0.925 -0.47)
			(stroke
				(width 0.05)
				(type default)
			)
			(fill no)
			(layer "B.CrtYd")
		)
		(fp_line
			(start -0.494 -0.248)
			(end -0.494 0.25)
			(stroke
				(width 0.15)
				(type solid)
			)
			(layer "B.Fab")
		)
		(fp_line
			(start -0.494 0.25)
			(end 0.504 0.25)
			(stroke
				(width 0.15)
				(type solid)
			)
			(layer "B.Fab")
		)
		(fp_line
			(start 0.504 -0.248)
			(end -0.494 -0.248)
			(stroke
				(width 0.15)
				(type solid)
			)
			(layer "B.Fab")
		)
		(fp_line
			(start 0.504 0.25)
			(end 0.504 -0.248)
			(stroke
				(width 0.15)
				(type solid)
			)
			(layer "B.Fab")
		)
		(pad "1" smd roundrect
			(at -0.48 0)
			(size 0.59 0.64)
			(layers "B.Cu" "B.Mask" "B.Paste")
			(roundrect_rratio 0.25)
			(net 1 "GND")
			(pintype "passive")
		)
		(pad "2" smd roundrect
			(at 0.48 0)
			(size 0.59 0.64)
			(layers "B.Cu" "B.Mask" "B.Paste")
			(roundrect_rratio 0.25)
			(net 26 "+1V8")
			(pintype "passive")
		)
	)
	(footprint "antmicro-footprints:C_0201"
		(layer "B.Cu")
		(at 201.5 129.65 180)
		(descr "Capacitor SMD 0201")
		(tags "capacitor SMD 0201")
		(property "Reference" "C52"
			(at -26.875 28.875 0)
			(layer "B.SilkS")
			(effects
				(font
					(size 0.7 0.7)
					(thickness 0.15)
				)
				(justify left bottom mirror)
			)
		)
		(property "Value" "C_4u7_0201"
			(at 0 -1.4 0)
			(layer "B.Fab")
			(effects
				(font
					(size 0.7 0.7)
					(thickness 0.15)
				)
				(justify left bottom mirror)
			)
		)
		(property "Description" "SMD Multilayer Ceramic Capacitor, 4.7 µF, 6.3 V, 0201 [0603 Metric], ± 20%, X5R, GRM Series"
			(at 0 0 180)
			(layer "F.Fab")
			(hide yes)
			(effects
				(font
					(size 1.27 1.27)
					(thickness 0.15)
				)
			)
		)
		(property "Author" "Antmicro"
			(at 403 259.3 0)
			(layer "B.Fab")
			(hide yes)
			(effects
				(font
					(size 1 1)
					(thickness 0.15)
				)
				(justify mirror)
			)
		)
		(property "Dielectric" ""
			(at 403 259.3 0)
			(layer "B.Fab")
			(hide yes)
			(effects
				(font
					(size 1 1)
					(thickness 0.15)
				)
				(justify mirror)
			)
		)
		(property "License" "Apache-2.0"
			(at 403 259.3 0)
			(layer "B.Fab")
			(hide yes)
			(effects
				(font
					(size 1 1)
					(thickness 0.15)
				)
				(justify mirror)
			)
		)
		(property "MPN" "GRM035R60J475ME15D"
			(at 403 259.3 0)
			(layer "B.Fab")
			(hide yes)
			(effects
				(font
					(size 1 1)
					(thickness 0.15)
				)
				(justify mirror)
			)
		)
		(property "Manufacturer" "Murata"
			(at 403 259.3 0)
			(layer "B.Fab")
			(hide yes)
			(effects
				(font
					(size 1 1)
					(thickness 0.15)
				)
				(justify mirror)
			)
		)
		(property "Val" "4u7"
			(at 403 259.3 0)
			(layer "B.Fab")
			(hide yes)
			(effects
				(font
					(size 1 1)
					(thickness 0.15)
				)
				(justify mirror)
			)
		)
		(property "Voltage" ""
			(at 403 259.3 0)
			(layer "B.Fab")
			(hide yes)
			(effects
				(font
					(size 1 1)
					(thickness 0.15)
				)
				(justify mirror)
			)
		)
		(sheetname "FPGA supply")
		(sheetfile "fpga-supply.kicad_sch")
		(attr smd)
		(fp_rect
			(start -0.7 0.35)
			(end 0.7 -0.35)
			(stroke
				(width 0.05)
				(type default)
			)
			(fill no)
			(layer "B.CrtYd")
		)
		(fp_rect
			(start 0.3 -0.15)
			(end -0.301 0.149)
			(stroke
				(width 0.15)
				(type solid)
			)
			(fill no)
			(layer "B.Fab")
		)
		(pad "" smd roundrect
			(at -0.349 0.002 180)
			(size 0.318 0.36)
			(layers "B.Paste")
			(roundrect_rratio 0.25)
		)
		(pad "" smd roundrect
			(at 0.341 0.002 180)
			(size 0.318 0.36)
			(layers "B.Paste")
			(roundrect_rratio 0.25)
		)
		(pad "1" smd roundrect
			(at -0.321 0.002 180)
			(size 0.46 0.4)
			(layers "B.Cu" "B.Mask")
			(roundrect_rratio 0.25)
			(net 1 "GND")
			(pintype "passive")
		)
		(pad "2" smd roundrect
			(at 0.32 0.002 180)
			(size 0.46 0.4)
			(layers "B.Cu" "B.Mask")
			(roundrect_rratio 0.25)
			(net 650 "+1V0")
			(pintype "passive")
		)
	)
)
